(kicad_pcb
	(version 20260206)
	(generator "pcbnew")
	(generator_version "10.0")
	(general
		(thickness 1.6)
		(legacy_teardrops no)
	)
	(paper "A4")
	(title_block
		(title "baseboard — 13948-1b.1110WZS1818.brd")
		(comment 1 "Honey Badger (Wiwynn) / footprints 1261-1267 of 2523")
	)
	(layers
		(0 "F.Cu" signal "TOP")
		(4 "In1.Cu" signal "L2GND")
		(6 "In2.Cu" signal "L3")
		(8 "In3.Cu" signal "L4VCC")
		(10 "In4.Cu" signal "L5VCC")
		(12 "In5.Cu" signal "L6")
		(14 "In6.Cu" signal "L7GND")
		(2 "B.Cu" signal "BOTTOM")
		(9 "F.Adhes" user "F.Adhesive")
		(11 "B.Adhes" user "B.Adhesive")
		(13 "F.Paste" user "Package Geometry/Pastemask Top")
		(15 "B.Paste" user "Package Geometry/Pastemask Bottom")
		(5 "F.SilkS" user "Ref Des/Silkscreen Top")
		(7 "B.SilkS" user "Ref Des/Silkscreen Bottom")
		(1 "F.Mask" user "Board Geometry/Soldermask Top")
		(3 "B.Mask" user "Board Geometry/Soldermask Bottom")
		(17 "Dwgs.User" user "User.Drawings")
		(19 "Cmts.User" user "User.Comments")
		(21 "Eco1.User" user "User.Eco1")
		(23 "Eco2.User" user "User.Eco2")
		(25 "Edge.Cuts" user "Board Geometry/Outline")
		(27 "Margin" user)
		(31 "F.CrtYd" user "Package Geometry/Place Bound Top")
		(29 "B.CrtYd" user "Package Geometry/Place Bound Bottom")
		(35 "F.Fab" user "Ref Des/Assembly Top")
		(33 "B.Fab" user "Ref Des/Assembly Bottom")
	)
	(footprint ""
		(layer "F.Cu")
		(at 193.167 -13.081 -90)
		(property "Reference" "R191"
			(at 0 0 270)
			(layer "F.SilkS")
			(hide yes)
			(effects
				(font
					(size 1.27 1.27)
				)
			)
		)
		(property "Value" "0R2J-2-GP"
			(at 0.064008 -3.993896 270)
			(unlocked yes)
			(layer "F.Fab")
			(hide yes)
			(effects
				(font
					(size 1.016 1.016)
					(thickness 0.1524)
				)
			)
		)
		(property "Device Type" "R402H16"
			(at 0.064008 -5.517896 270)
			(unlocked yes)
			(layer "F.Fab")
			(hide yes)
			(effects
				(font
					(size 1.016 1.016)
					(thickness 0.1524)
				)
			)
		)
		(duplicate_pad_numbers_are_jumpers no)
		(fp_line
			(start -0.508 -0.9398)
			(end -0.508 0.9398)
			(stroke
				(width 0.1524)
				(type default)
			)
			(layer "F.SilkS")
		)
		(fp_line
			(start 0.508 -0.9398)
			(end -0.508 -0.9398)
			(stroke
				(width 0.1524)
				(type default)
			)
			(layer "F.SilkS")
		)
		(fp_rect
			(start -0.508 0.9398)
			(end 0.508 -0.9398)
			(stroke
				(width 0)
				(type default)
			)
			(fill no)
			(layer "F.CrtYd")
		)
		(fp_rect
			(start -0.508 0.9398)
			(end 0.508 -0.9398)
			(stroke
				(width 0)
				(type default)
			)
			(fill no)
			(layer "F.Fab")
		)
		(pad "1" smd custom
			(at 0 -0.4445 270)
			(size 0.1397 0.1397)
			(layers "F.Cu" "F.Mask" "F.Paste")
			(net "BMC_I2C_D_SDA")
			(options
				(clearance outline)
				(anchor circle)
			)
			(primitives
				(gr_poly
					(pts
						(arc
							(start -0.1778 -0.2794)
							(mid -0.249642 -0.249642)
							(end -0.2794 -0.1778)
						)
						(arc
							(start -0.2794 0.1778)
							(mid -0.249642 0.249642)
							(end -0.1778 0.2794)
						)
						(arc
							(start 0.1778 0.2794)
							(mid 0.249642 0.249642)
							(end 0.2794 0.1778)
						)
						(arc
							(start 0.2794 -0.1778)
							(mid 0.249642 -0.249642)
							(end 0.1778 -0.2794)
						)
					)
					(width 0)
					(fill yes)
				)
			)
		)
		(pad "2" smd custom
			(at 0 0.4445 270)
			(size 0.1397 0.1397)
			(layers "F.Cu" "F.Mask" "F.Paste")
			(net "TEMP_1_SDA")
			(options
				(clearance outline)
				(anchor circle)
			)
			(primitives
				(gr_poly
					(pts
						(arc
							(start -0.1778 -0.2794)
							(mid -0.249642 -0.249642)
							(end -0.2794 -0.1778)
						)
						(arc
							(start -0.2794 0.1778)
							(mid -0.249642 0.249642)
							(end -0.1778 0.2794)
						)
						(arc
							(start 0.1778 0.2794)
							(mid 0.249642 0.249642)
							(end 0.2794 0.1778)
						)
						(arc
							(start 0.2794 -0.1778)
							(mid 0.249642 -0.249642)
							(end 0.1778 -0.2794)
						)
					)
					(width 0)
					(fill yes)
				)
			)
		)
	)
	(footprint ""
		(layer "F.Cu")
		(at 279.264872 -225.116136 180)
		(property "Reference" "PC78"
			(at 0 0 180)
			(layer "F.SilkS")
			(hide yes)
			(effects
				(font
					(size 1.27 1.27)
				)
			)
		)
		(property "Value" "SCD1U16V2KX-3GP"
			(at 1.1811 -2.7051 180)
			(unlocked yes)
			(layer "F.Fab")
			(hide yes)
			(effects
				(font
					(size 1.016 1.016)
					(thickness 0.1524)
				)
			)
		)
		(property "Device Type" "C402H22"
			(at 1.1811 -4.2291 180)
			(unlocked yes)
			(layer "F.Fab")
			(hide yes)
			(effects
				(font
					(size 1.016 1.016)
					(thickness 0.1524)
				)
			)
		)
		(duplicate_pad_numbers_are_jumpers no)
		(fp_rect
			(start -0.4318 0.9525)
			(end 0.4318 -0.9525)
			(stroke
				(width 0)
				(type default)
			)
			(fill no)
			(layer "F.CrtYd")
		)
		(fp_rect
			(start -0.4318 0.9525)
			(end 0.4318 -0.9525)
			(stroke
				(width 0)
				(type default)
			)
			(fill no)
			(layer "F.Fab")
		)
		(pad "1" smd custom
			(at 0 -0.4445 180)
			(size 0.1524 0.1524)
			(layers "F.Cu" "F.Mask" "F.Paste")
			(net "TPS74801_P1V53_STBY_IN")
			(options
				(clearance outline)
				(anchor circle)
			)
			(primitives
				(gr_poly
					(pts
						(arc
							(start 0.3048 -0.2032)
							(mid 0.275042 -0.275042)
							(end 0.2032 -0.3048)
						)
						(arc
							(start -0.2032 -0.3048)
							(mid -0.275042 -0.275042)
							(end -0.3048 -0.2032)
						)
						(arc
							(start -0.3048 0.2032)
							(mid -0.275042 0.275042)
							(end -0.2032 0.3048)
						)
						(arc
							(start 0.2032 0.3048)
							(mid 0.275042 0.275042)
							(end 0.3048 0.2032)
						)
					)
					(width 0)
					(fill yes)
				)
			)
		)
		(pad "2" smd custom
			(at 0 0.4445 180)
			(size 0.1524 0.1524)
			(layers "F.Cu" "F.Mask" "F.Paste")
			(net "GND")
			(options
				(clearance outline)
				(anchor circle)
			)
			(primitives
				(gr_poly
					(pts
						(arc
							(start 0.3048 -0.2032)
							(mid 0.275042 -0.275042)
							(end 0.2032 -0.3048)
						)
						(arc
							(start -0.2032 -0.3048)
							(mid -0.275042 -0.275042)
							(end -0.3048 -0.2032)
						)
						(arc
							(start -0.3048 0.2032)
							(mid -0.275042 0.275042)
							(end -0.2032 0.3048)
						)
						(arc
							(start 0.2032 0.3048)
							(mid 0.275042 0.275042)
							(end 0.3048 0.2032)
						)
					)
					(width 0)
					(fill yes)
				)
			)
		)
	)
	(footprint ""
		(layer "F.Cu")
		(at 315.214 -196.977 180)
		(property "Reference" "U181"
			(at 0 0 180)
			(layer "F.SilkS")
			(hide yes)
			(effects
				(font
					(size 1.27 1.27)
				)
			)
		)
		(property "Value" "SN74AVC4T774RGYR-GP"
			(at -3.774948 -0.185674 180)
			(unlocked yes)
			(layer "F.Fab")
			(hide yes)
			(effects
				(font
					(size 1.016 1.016)
					(thickness 0.1524)
				)
			)
		)
		(property "Device Type" "QFN16G3540-G215265H40"
			(at -3.774948 -1.709674 180)
			(unlocked yes)
			(layer "F.Fab")
			(hide yes)
			(effects
				(font
					(size 1.016 1.016)
					(thickness 0.1524)
				)
			)
		)
		(duplicate_pad_numbers_are_jumpers no)
		(fp_line
			(start 3.0099 2.7686)
			(end 1.7399 2.7686)
			(stroke
				(width 0.1524)
				(type default)
			)
			(layer "F.SilkS")
		)
		(fp_line
			(start 3.0099 1.4986)
			(end 3.0099 2.7686)
			(stroke
				(width 0.1524)
				(type default)
			)
			(layer "F.SilkS")
		)
		(fp_line
			(start 1.249934 2.54)
			(end 1.249934 3.048)
			(stroke
				(width 0.1524)
				(type default)
			)
			(layer "F.SilkS")
		)
		(fp_line
			(start -0.249936 -2.54)
			(end -0.249936 -3.048)
			(stroke
				(width 0.1524)
				(type default)
			)
			(layer "F.SilkS")
		)
		(fp_line
			(start -1.249934 2.54)
			(end -1.249934 3.302)
			(stroke
				(width 0.1524)
				(type default)
			)
			(layer "F.SilkS")
		)
		(fp_line
			(start -3.0099 2.7686)
			(end -1.7399 2.7686)
			(stroke
				(width 0.1524)
				(type default)
			)
			(layer "F.SilkS")
		)
		(fp_line
			(start -3.0099 1.4986)
			(end -3.0099 2.7686)
			(stroke
				(width 0.1524)
				(type default)
			)
			(layer "F.SilkS")
		)
		(fp_line
			(start -3.0099 -1.4986)
			(end -3.0099 -2.7686)
			(stroke
				(width 0.1524)
				(type default)
			)
			(layer "F.SilkS")
		)
		(fp_line
			(start -3.0099 -2.7686)
			(end -1.7399 -2.7686)
			(stroke
				(width 0.1524)
				(type default)
			)
			(layer "F.SilkS")
		)
		(fp_poly
			(pts
				(xy 1.7399 -2.7686) (xy 3.0099 -1.4986) (xy 3.0099 -2.7686)
			)
			(stroke
				(width 0)
				(type default)
			)
			(fill yes)
			(layer "F.SilkS")
		)
		(fp_rect
			(start -1.9939 1.7526)
			(end 1.9939 -1.7526)
			(stroke
				(width 0)
				(type default)
			)
			(fill no)
			(layer "F.CrtYd")
		)
		(fp_poly
			(pts
				(xy -3.0099 2.7686) (xy -3.0099 -2.7686) (xy 3.0099 -2.7686) (xy 3.0099 -0.2286) (xy 1.9939 -0.2286)
				(xy 1.9939 -1.7526) (xy -1.9939 -1.7526) (xy -1.9939 1.7526) (xy 1.9939 1.7526) (xy 1.9939 -0.22352)
				(xy 3.0099 -0.22352) (xy 3.0099 2.7686)
			)
			(stroke
				(width 0)
				(type default)
			)
			(fill no)
			(layer "F.CrtYd")
		)
		(fp_rect
			(start -3.0099 2.7686)
			(end 3.0099 -2.7686)
			(stroke
				(width 0)
				(type default)
			)
			(fill no)
			(layer "F.Fab")
		)
		(pad "1" smd rect
			(at 2.0193 -0.750062 180)
			(size 0.9652 0.3048)
			(layers "F.Cu" "F.Mask" "F.Paste")
			(net "P3V3_STBY")
		)
		(pad "2" smd rect
			(at 1.249934 -1.778 180)
			(size 0.3048 0.9652)
			(layers "F.Cu" "F.Mask" "F.Paste")
			(net "P3V3_STBY")
		)
		(pad "3" smd rect
			(at 0.750062 -1.778 180)
			(size 0.3048 0.9652)
			(layers "F.Cu" "F.Mask" "F.Paste")
			(net "JTAG_BMC_TRST_N")
		)
		(pad "4" smd rect
			(at 0.249936 -1.778 180)
			(size 0.3048 0.9652)
			(layers "F.Cu" "F.Mask" "F.Paste")
			(net "JTAG_BMC_TMS")
		)
		(pad "5" smd rect
			(at -0.249936 -1.778 180)
			(size 0.3048 0.9652)
			(layers "F.Cu" "F.Mask" "F.Paste")
			(net "JTAG_BMC_TCK")
		)
		(pad "6" smd rect
			(at -0.750062 -1.778 180)
			(size 0.3048 0.9652)
			(layers "F.Cu" "F.Mask" "F.Paste")
			(net "JTAG_BMC_TDO")
		)
		(pad "7" smd rect
			(at -1.249934 -1.778 180)
			(size 0.3048 0.9652)
			(layers "F.Cu" "F.Mask" "F.Paste")
			(net "P3V3_STBY")
		)
		(pad "8" smd rect
			(at -2.0193 -0.750062 180)
			(size 0.9652 0.3048)
			(layers "F.Cu" "F.Mask" "F.Paste")
			(net "P3V3_STBY")
		)
		(pad "9" smd rect
			(at -2.0193 0.75311 180)
			(size 0.9652 0.3048)
			(layers "F.Cu" "F.Mask" "F.Paste")
			(net "BMC_JTAG_L_EN")
		)
		(pad "10" smd rect
			(at -1.249934 1.778 180)
			(size 0.3048 0.9652)
			(layers "F.Cu" "F.Mask" "F.Paste")
			(net "GND")
		)
		(pad "11" smd rect
			(at -0.750062 1.778 180)
			(size 0.3048 0.9652)
			(layers "F.Cu" "F.Mask" "F.Paste")
			(net "JTAG_BMC_L_TDO")
		)
		(pad "12" smd rect
			(at -0.249936 1.778 180)
			(size 0.3048 0.9652)
			(layers "F.Cu" "F.Mask" "F.Paste")
			(net "JTAG_EXP_IOC_TCK")
		)
		(pad "13" smd rect
			(at 0.249936 1.778 180)
			(size 0.3048 0.9652)
			(layers "F.Cu" "F.Mask" "F.Paste")
			(net "JTAG_EXP_IOC_TMS")
		)
		(pad "14" smd rect
			(at 0.750062 1.778 180)
			(size 0.3048 0.9652)
			(layers "F.Cu" "F.Mask" "F.Paste")
			(net "JTAG_EXP_IOC_RST")
		)
		(pad "15" smd rect
			(at 1.249934 1.778 180)
			(size 0.3048 0.9652)
			(layers "F.Cu" "F.Mask" "F.Paste")
			(net "P1V8_STBY")
		)
		(pad "16" smd rect
			(at 2.0193 0.750062 180)
			(size 0.9652 0.3048)
			(layers "F.Cu" "F.Mask" "F.Paste")
			(net "P3V3_STBY")
		)
		(pad "17" smd rect
			(at 0 0 180)
			(size 2.6416 2.159)
			(layers "F.Cu" "F.Mask" "F.Paste")
			(net "GND")
		)
	)
	(footprint ""
		(layer "F.Cu")
		(at 270.891 -44.958 180)
		(property "Reference" "PC43"
			(at 0 0 180)
			(layer "F.SilkS")
			(hide yes)
			(effects
				(font
					(size 1.27 1.27)
				)
			)
		)
		(property "Value" "SC22U25V5MX-GP"
			(at -0.0762 -6.1214 180)
			(unlocked yes)
			(layer "F.Fab")
			(hide yes)
			(effects
				(font
					(size 1.016 1.016)
					(thickness 0.1524)
				)
			)
		)
		(property "Device Type" "C805H58"
			(at -0.0762 -8.1534 180)
			(unlocked yes)
			(layer "F.Fab")
			(hide yes)
			(effects
				(font
					(size 1.016 1.016)
					(thickness 0.1524)
				)
			)
		)
		(duplicate_pad_numbers_are_jumpers no)
		(fp_line
			(start 0.635 0)
			(end -0.635 0)
			(stroke
				(width 0.508)
				(type default)
			)
			(layer "F.SilkS")
		)
		(fp_rect
			(start -0.9652 1.778)
			(end 0.9652 -1.778)
			(stroke
				(width 0)
				(type default)
			)
			(fill no)
			(layer "F.CrtYd")
		)
		(fp_poly
			(pts
				(xy -0.9652 -1.778) (xy 0.9652 -1.778) (xy 0.9652 1.778) (xy -0.9652 1.778)
			)
			(stroke
				(width 0)
				(type default)
			)
			(fill no)
			(layer "F.Fab")
		)
		(pad "1" smd rect
			(at 0 -0.9652 180)
			(size 1.397 1.143)
			(layers "F.Cu" "F.Mask" "F.Paste")
			(net "P1V8_STBY_VIN")
		)
		(pad "2" smd rect
			(at 0 0.9652 180)
			(size 1.397 1.143)
			(layers "F.Cu" "F.Mask" "F.Paste")
			(net "GND")
		)
	)
	(footprint ""
		(layer "F.Cu")
		(at 226.568 -17.907 -90)
		(property "Reference" "R543"
			(at 0 0 270)
			(layer "F.SilkS")
			(hide yes)
			(effects
				(font
					(size 1.27 1.27)
				)
			)
		)
		(property "Value" "330R1210J-GP"
			(at 0.0889 -6.9977 270)
			(unlocked yes)
			(layer "F.Fab")
			(hide yes)
			(effects
				(font
					(size 1.016 1.016)
					(thickness 0.1524)
				)
			)
		)
		(property "Device Type" "R1210H24"
			(at 0.0635 -8.636 270)
			(unlocked yes)
			(layer "F.Fab")
			(hide yes)
			(effects
				(font
					(size 1.016 1.016)
					(thickness 0.1524)
				)
			)
		)
		(duplicate_pad_numbers_are_jumpers no)
		(fp_line
			(start -1.651 2.413)
			(end -1.651 -2.413)
			(stroke
				(width 0.1524)
				(type default)
			)
			(layer "F.SilkS")
		)
		(fp_line
			(start 1.651 2.413)
			(end -1.651 2.413)
			(stroke
				(width 0.1524)
				(type default)
			)
			(layer "F.SilkS")
		)
		(fp_line
			(start -1.651 -2.413)
			(end 1.651 -2.413)
			(stroke
				(width 0.1524)
				(type default)
			)
			(layer "F.SilkS")
		)
		(fp_line
			(start 1.651 -2.413)
			(end 1.651 2.413)
			(stroke
				(width 0.1524)
				(type default)
			)
			(layer "F.SilkS")
		)
		(fp_poly
			(pts
				(xy -1.651 -2.413) (xy 1.651 -2.413) (xy 1.651 2.413) (xy -1.651 2.413)
			)
			(stroke
				(width 0)
				(type default)
			)
			(fill no)
			(layer "F.CrtYd")
		)
		(fp_poly
			(pts
				(xy -1.651 -2.413) (xy 1.651 -2.413) (xy 1.651 2.413) (xy -1.651 2.413)
			)
			(stroke
				(width 0)
				(type default)
			)
			(fill no)
			(layer "F.Fab")
		)
		(pad "1" smd rect
			(at 0 -1.4732 270)
			(size 2.794 1.397)
			(layers "F.Cu" "F.Mask" "F.Paste")
			(net "P5V_STBY")
		)
		(pad "2" smd rect
			(at 0 1.4732 270)
			(size 2.794 1.397)
			(layers "F.Cu" "F.Mask" "F.Paste")
			(net "ENCLO_LED_RED_R")
		)
	)
	(footprint ""
		(layer "F.Cu")
		(at 319.913 -165.354 -90)
		(property "Reference" "R492"
			(at 0 0 270)
			(layer "F.SilkS")
			(hide yes)
			(effects
				(font
					(size 1.27 1.27)
				)
			)
		)
		(property "Value" "10KR2F-2-GP"
			(at 0.064008 -3.993896 270)
			(unlocked yes)
			(layer "F.Fab")
			(hide yes)
			(effects
				(font
					(size 1.016 1.016)
					(thickness 0.1524)
				)
			)
		)
		(property "Device Type" "R402H16"
			(at 0.064008 -5.517896 270)
			(unlocked yes)
			(layer "F.Fab")
			(hide yes)
			(effects
				(font
					(size 1.016 1.016)
					(thickness 0.1524)
				)
			)
		)
		(duplicate_pad_numbers_are_jumpers no)
		(fp_line
			(start -0.508 -0.9398)
			(end -0.508 0.9398)
			(stroke
				(width 0.1524)
				(type default)
			)
			(layer "F.SilkS")
		)
		(fp_line
			(start 0.508 -0.9398)
			(end -0.508 -0.9398)
			(stroke
				(width 0.1524)
				(type default)
			)
			(layer "F.SilkS")
		)
		(fp_rect
			(start -0.508 0.9398)
			(end 0.508 -0.9398)
			(stroke
				(width 0)
				(type default)
			)
			(fill no)
			(layer "F.CrtYd")
		)
		(fp_rect
			(start -0.508 0.9398)
			(end 0.508 -0.9398)
			(stroke
				(width 0)
				(type default)
			)
			(fill no)
			(layer "F.Fab")
		)
		(pad "1" smd custom
			(at 0 -0.4445 270)
			(size 0.1397 0.1397)
			(layers "F.Cu" "F.Mask" "F.Paste")
			(net "P3V3_STBY")
			(options
				(clearance outline)
				(anchor circle)
			)
			(primitives
				(gr_poly
					(pts
						(arc
							(start -0.1778 -0.2794)
							(mid -0.249642 -0.249642)
							(end -0.2794 -0.1778)
						)
						(arc
							(start -0.2794 0.1778)
							(mid -0.249642 0.249642)
							(end -0.1778 0.2794)
						)
						(arc
							(start 0.1778 0.2794)
							(mid 0.249642 0.249642)
							(end 0.2794 0.1778)
						)
						(arc
							(start 0.2794 -0.1778)
							(mid 0.249642 -0.249642)
							(end 0.1778 -0.2794)
						)
					)
					(width 0)
					(fill yes)
				)
			)
		)
		(pad "2" smd custom
			(at 0 0.4445 270)
			(size 0.1397 0.1397)
			(layers "F.Cu" "F.Mask" "F.Paste")
			(net "BMC_I2C_C_SCL")
			(options
				(clearance outline)
				(anchor circle)
			)
			(primitives
				(gr_poly
					(pts
						(arc
							(start -0.1778 -0.2794)
							(mid -0.249642 -0.249642)
							(end -0.2794 -0.1778)
						)
						(arc
							(start -0.2794 0.1778)
							(mid -0.249642 0.249642)
							(end -0.1778 0.2794)
						)
						(arc
							(start 0.1778 0.2794)
							(mid 0.249642 0.249642)
							(end 0.2794 0.1778)
						)
						(arc
							(start 0.2794 -0.1778)
							(mid 0.249642 -0.249642)
							(end 0.1778 -0.2794)
						)
					)
					(width 0)
					(fill yes)
				)
			)
		)
	)
	(footprint ""
		(layer "F.Cu")
		(at 117.837966 -48.133 -90)
		(property "Reference" "SR649"
			(at 0 0 270)
			(layer "F.SilkS")
			(hide yes)
			(effects
				(font
					(size 1.27 1.27)
				)
			)
		)
		(property "Value" "10KR2F-2-GP"
			(at 0.064008 -3.993896 270)
			(unlocked yes)
			(layer "F.Fab")
			(hide yes)
			(effects
				(font
					(size 1.016 1.016)
					(thickness 0.1524)
				)
			)
		)
		(property "Device Type" "R402H16"
			(at 0.064008 -5.517896 270)
			(unlocked yes)
			(layer "F.Fab")
			(hide yes)
			(effects
				(font
					(size 1.016 1.016)
					(thickness 0.1524)
				)
			)
		)
		(duplicate_pad_numbers_are_jumpers no)
		(fp_line
			(start -0.508 -0.9398)
			(end -0.508 0.9398)
			(stroke
				(width 0.1524)
				(type default)
			)
			(layer "F.SilkS")
		)
		(fp_line
			(start 0.508 -0.9398)
			(end -0.508 -0.9398)
			(stroke
				(width 0.1524)
				(type default)
			)
			(layer "F.SilkS")
		)
		(fp_rect
			(start -0.508 0.9398)
			(end 0.508 -0.9398)
			(stroke
				(width 0)
				(type default)
			)
			(fill no)
			(layer "F.CrtYd")
		)
		(fp_rect
			(start -0.508 0.9398)
			(end 0.508 -0.9398)
			(stroke
				(width 0)
				(type default)
			)
			(fill no)
			(layer "F.Fab")
		)
		(pad "1" smd custom
			(at 0 -0.4445 270)
			(size 0.1397 0.1397)
			(layers "F.Cu" "F.Mask" "F.Paste")
			(net "GND")
			(options
				(clearance outline)
				(anchor circle)
			)
			(primitives
				(gr_poly
					(pts
						(arc
							(start -0.1778 -0.2794)
							(mid -0.249642 -0.249642)
							(end -0.2794 -0.1778)
						)
						(arc
							(start -0.2794 0.1778)
							(mid -0.249642 0.249642)
							(end -0.1778 0.2794)
						)
						(arc
							(start 0.1778 0.2794)
							(mid 0.249642 0.249642)
							(end 0.2794 0.1778)
						)
						(arc
							(start 0.2794 -0.1778)
							(mid 0.249642 -0.249642)
							(end 0.1778 -0.2794)
						)
					)
					(width 0)
					(fill yes)
				)
			)
		)
		(pad "2" smd custom
			(at 0 0.4445 270)
			(size 0.1397 0.1397)
			(layers "F.Cu" "F.Mask" "F.Paste")
			(net "MEM_CLK_SEL")
			(options
				(clearance outline)
				(anchor circle)
			)
			(primitives
				(gr_poly
					(pts
						(arc
							(start -0.1778 -0.2794)
							(mid -0.249642 -0.249642)
							(end -0.2794 -0.1778)
						)
						(arc
							(start -0.2794 0.1778)
							(mid -0.249642 0.249642)
							(end -0.1778 0.2794)
						)
						(arc
							(start 0.1778 0.2794)
							(mid 0.249642 0.249642)
							(end 0.2794 0.1778)
						)
						(arc
							(start 0.2794 -0.1778)
							(mid 0.249642 -0.249642)
							(end 0.1778 -0.2794)
						)
					)
					(width 0)
					(fill yes)
				)
			)
		)
	)
)
